#ISCELL
  mstr_misc dns *
  *
#ISCELL
  mstr_symbols design_note *
  *
#ISCELL
  mstr_symbols intel_corp_bpage *
  *
#CELL
  mstr_discrete res *
  page125_i11
#ISCELL
  mstr_symbols gnd *
  page125_i14
#CELL
  mstr_discrete res *
  page125_i15
#ISCELL
  mstr_symbols gnd *
  page125_i16
#ISCELL
  mstr_standard offpage *
  page125_i20
#CELL
  mstr_discrete res *
  page125_i21
#ISCELL
  mstr_standard offpage *
  page125_i23
#CELL
  mstr_discrete res *
  page125_i24
#ISCELL
  mstr_symbols gnd *
  page125_i25
#CELL
  mstr_discrete res *
  page125_i40
#CELL
  mstr_discrete res *
  page125_i41
#ISCELL
  mstr_standard offpage *
  page125_i43
#ISCELL
  mstr_symbols p3v3_stby *
  page125_i48
#ISCELL
  mstr_symbols p3v3_stby *
  page125_i49
#CELL
  mstr_discrete res *
  page125_i50
#ISCELL
  mstr_symbols p3v3_stby *
  page125_i51
#CELL
  mstr_discrete res *
  page125_i52
#ISCELL
  mstr_standard offpage *
  page125_i53
#ISCELL
  mstr_symbols gnd *
  page125_i54
#ISCELL
  mstr_symbols gnd *
  page125_i6
#CELL
  mstr_discrete res *
  page125_i60
#ISCELL
  mstr_symbols p3v3_stby *
  page125_i61
#ISCELL
  mstr_standard offpage *
  page125_i64
#ISCELL
  mstr_standard offpage *
  page125_i65
#ISCELL
  mstr_symbols p3v3_stby *
  page125_i66
#ISCELL
  mstr_symbols gnd *
  page125_i69
#ISCELL
  mstr_standard offpage *
  page125_i7
#CELL
  mstr_discrete res *
  page125_i70
#CELL
  mstr_discrete res *
  page125_i71
#CELL
  mstr_discrete res *
  page125_i72
#ISCELL
  mstr_standard offpage *
  page125_i73
#ISCELL
  mstr_symbols p3v3_stby *
  page125_i74
#ISCELL
  mstr_symbols p3v3_stby *
  page125_i75
#CELL
  mstr_discrete res *
  page125_i76
#ISCELL
  mstr_standard offpage *
  page125_i77
#CELL
  mstr_discrete res *
  page125_i78
#ISCELL
  mstr_symbols p3v3_stby *
  page125_i79
#ISCELL
  mstr_standard offpage *
  page125_i82
#CELL
  mstr_discrete res *
  page125_i83
#ISCELL
  mstr_symbols p3v3_stby *
  page125_i84
